# S9S_MB_2U (Grand Teton) — schematic netlist excerpt (pin names and nets, part order shuffled) for the footprints in the layout excerpt that follows; sources: Cadence DE-HDL packaged netlist, KiCad conversion of 03242023_DA0F0TMBIJ0_F0T_Motherboard_J_brd_V01_OCP.brd

D87  Q_LED  IC  pkg SMLF  page 255 : A = LED_PWRGD_PCH_PWROK_R ; C = LED_PWRGD_PCH_PWROK_R_D
R1016  Q_RES  0 5% CHIP  pkg 0402LF  page 209 : A = CLK_25M_CK440_CPU1_DP ; B = CLK_25M_CK440_CPU1_R_DP

(kicad_pcb
	(version 20260206)
	(generator "pcbnew")
	(generator_version "10.0")
	(general
		(thickness 1.6)
		(legacy_teardrops no)
	)
	(paper "A4")
	(title_block
		(title "03242023_DA0F0TMBIJ0_F0T_Motherboard_J_brd_V01_OCP.brd")
		(comment 1 "Grand Teton / footprints 943-944 of 6105")
	)
	(layers
		(0 "F.Cu" signal "TOP")
		(4 "In1.Cu" signal "GND")
		(6 "In2.Cu" signal "IN1")
		(8 "In3.Cu" signal "GND1")
		(10 "In4.Cu" signal "IN2")
		(12 "In5.Cu" signal "GND2")
		(14 "In6.Cu" signal "IN3")
		(16 "In7.Cu" signal "GND3")
		(18 "In8.Cu" signal "VCC")
		(20 "In9.Cu" signal "VCC1")
		(22 "In10.Cu" signal "GND4")
		(24 "In11.Cu" signal "IN4")
		(26 "In12.Cu" signal "GND5")
		(28 "In13.Cu" signal "IN5")
		(30 "In14.Cu" signal "GND6")
		(32 "In15.Cu" signal "IN6")
		(34 "In16.Cu" signal "GND7")
		(2 "B.Cu" signal "BOTTOM")
		(9 "F.Adhes" user "F.Adhesive")
		(11 "B.Adhes" user "B.Adhesive")
		(13 "F.Paste" user "Package Geometry/Pastemask Top")
		(15 "B.Paste" user "Package Geometry/Pastemask Bottom")
		(5 "F.SilkS" user "Ref Des/Silkscreen Top")
		(7 "B.SilkS" user "Ref Des/Silkscreen Bottom")
		(1 "F.Mask" user "Board Geometry/Soldermask Top")
		(3 "B.Mask" user "Board Geometry/Soldermask Bottom")
		(17 "Dwgs.User" user "User.Drawings")
		(19 "Cmts.User" user "User.Comments")
		(21 "Eco1.User" user "User.Eco1")
		(23 "Eco2.User" user "User.Eco2")
		(25 "Edge.Cuts" user "Board Geometry/Outline")
		(27 "Margin" user)
		(31 "F.CrtYd" user "Package Geometry/Place Bound Top")
		(29 "B.CrtYd" user "Package Geometry/Place Bound Bottom")
		(35 "F.Fab" user "Ref Des/Assembly Top")
		(33 "B.Fab" user "Ref Des/Assembly Bottom")
	)
	(footprint ""
		(layer "F.Cu")
		(at 241.308128 -110.240572 180)
		(property "Reference" "R1016"
			(at 0 0 180)
			(layer "F.SilkS")
			(hide yes)
			(effects
				(font
					(size 1.27 1.27)
				)
			)
		)
		(property "Value" ""
			(at 0 0 180)
			(layer "F.Fab")
			(effects
				(font
					(size 1.27 1.27)
				)
			)
		)
		(duplicate_pad_numbers_are_jumpers no)
		(fp_line
			(start 0.7874 0.4064)
			(end -0.7874 0.4064)
			(stroke
				(width 0.1524)
				(type default)
			)
			(layer "F.SilkS")
		)
		(fp_line
			(start 0.7874 -0.4064)
			(end 0.7874 0.4064)
			(stroke
				(width 0.1524)
				(type default)
			)
			(layer "F.SilkS")
		)
		(fp_line
			(start -0.7874 0.4064)
			(end -0.7874 -0.4064)
			(stroke
				(width 0.1524)
				(type default)
			)
			(layer "F.SilkS")
		)
		(fp_line
			(start -0.7874 -0.4064)
			(end 0.7874 -0.4064)
			(stroke
				(width 0.1524)
				(type default)
			)
			(layer "F.SilkS")
		)
		(fp_line
			(start 0.67945 0.3048)
			(end 0.120396 0.3048)
			(stroke
				(width 0.1)
				(type default)
			)
			(layer "F.Fab")
		)
		(fp_line
			(start 0.67945 -0.3048)
			(end 0.67945 0.3048)
			(stroke
				(width 0.1)
				(type default)
			)
			(layer "F.Fab")
		)
		(fp_line
			(start 0.12065 -0.2794)
			(end 0.12065 -0.3048)
			(stroke
				(width 0.1)
				(type default)
			)
			(layer "F.Fab")
		)
		(fp_line
			(start 0.12065 -0.3048)
			(end 0.67945 -0.3048)
			(stroke
				(width 0.1)
				(type default)
			)
			(layer "F.Fab")
		)
		(fp_line
			(start 0.120396 0.3048)
			(end 0.120396 0.2794)
			(stroke
				(width 0.1)
				(type default)
			)
			(layer "F.Fab")
		)
		(fp_line
			(start 0.120396 0.2794)
			(end -0.12065 0.2794)
			(stroke
				(width 0.1)
				(type default)
			)
			(layer "F.Fab")
		)
		(fp_line
			(start -0.12065 0.3048)
			(end -0.67945 0.3048)
			(stroke
				(width 0.1)
				(type default)
			)
			(layer "F.Fab")
		)
		(fp_line
			(start -0.12065 0.2794)
			(end -0.12065 0.3048)
			(stroke
				(width 0.1)
				(type default)
			)
			(layer "F.Fab")
		)
		(fp_line
			(start -0.12065 -0.2794)
			(end 0.12065 -0.2794)
			(stroke
				(width 0.1)
				(type default)
			)
			(layer "F.Fab")
		)
		(fp_line
			(start -0.12065 -0.305054)
			(end -0.12065 -0.2794)
			(stroke
				(width 0.1)
				(type default)
			)
			(layer "F.Fab")
		)
		(fp_line
			(start -0.67945 0.3048)
			(end -0.67945 -0.305054)
			(stroke
				(width 0.1)
				(type default)
			)
			(layer "F.Fab")
		)
		(fp_line
			(start -0.67945 -0.305054)
			(end -0.12065 -0.305054)
			(stroke
				(width 0.1)
				(type default)
			)
			(layer "F.Fab")
		)
		(pad "1" smd circle
			(at -0.40005 0 180)
			(size 0 0)
			(layers "F.Cu" "F.Mask" "F.Paste")
			(net "CLK_25M_CK440_CPU1_DP")
		)
		(pad "2" smd circle
			(at 0.40005 0 180)
			(size 0 0)
			(layers "F.Cu" "F.Mask" "F.Paste")
			(net "CLK_25M_CK440_CPU1_R_DP")
		)
	)
	(footprint ""
		(layer "F.Cu")
		(at 93.782896 -70.78599)
		(property "Reference" "D87"
			(at -47.431706 50.178462 90)
			(unlocked yes)
			(layer "F.SilkS")
			(effects
				(font
					(size 0.635 0.4064)
					(thickness 0.1524)
				)
				(justify left)
			)
		)
		(property "Value" ""
			(at 0 0 0)
			(layer "F.Fab")
			(effects
				(font
					(size 1.27 1.27)
				)
			)
		)
		(duplicate_pad_numbers_are_jumpers no)
		(fp_line
			(start -0.90678 0.4826)
			(end -0.90678 -0.4699)
			(stroke
				(width 0.1524)
				(type default)
			)
			(layer "F.SilkS")
		)
		(fp_line
			(start -0.89408 -0.4826)
			(end 0.90678 -0.4826)
			(stroke
				(width 0.1524)
				(type default)
			)
			(layer "F.SilkS")
		)
		(fp_line
			(start -0.79248 -0.4826)
			(end 1.03378 -0.4826)
			(stroke
				(width 0.1524)
				(type default)
			)
			(layer "F.SilkS")
		)
		(fp_line
			(start -0.64008 -0.4826)
			(end 1.16078 -0.4826)
			(stroke
				(width 0.1524)
				(type default)
			)
			(layer "F.SilkS")
		)
		(fp_line
			(start 0.90678 -0.4826)
			(end 0.90678 0.4826)
			(stroke
				(width 0.1524)
				(type default)
			)
			(layer "F.SilkS")
		)
		(fp_line
			(start 0.90678 0.4826)
			(end -0.90678 0.4826)
			(stroke
				(width 0.1524)
				(type default)
			)
			(layer "F.SilkS")
		)
		(fp_line
			(start 1.03378 -0.4826)
			(end 1.03378 0.4826)
			(stroke
				(width 0.1524)
				(type default)
			)
			(layer "F.SilkS")
		)
		(fp_line
			(start 1.03378 0.4826)
			(end -0.79248 0.4826)
			(stroke
				(width 0.1524)
				(type default)
			)
			(layer "F.SilkS")
		)
		(fp_line
			(start 1.16078 -0.4826)
			(end 1.16078 0.4826)
			(stroke
				(width 0.1524)
				(type default)
			)
			(layer "F.SilkS")
		)
		(fp_line
			(start 1.16078 0.4826)
			(end -0.64008 0.4826)
			(stroke
				(width 0.1524)
				(type default)
			)
			(layer "F.SilkS")
		)
		(fp_line
			(start -0.499872 -0.249936)
			(end 0.499872 -0.249936)
			(stroke
				(width 0.1)
				(type default)
			)
			(layer "F.Fab")
		)
		(fp_line
			(start -0.499872 0.249936)
			(end -0.499872 -0.249936)
			(stroke
				(width 0.1)
				(type default)
			)
			(layer "F.Fab")
		)
		(fp_line
			(start 0.499872 -0.249936)
			(end 0.499872 0.249936)
			(stroke
				(width 0.1)
				(type default)
			)
			(layer "F.Fab")
		)
		(fp_line
			(start 0.499872 0.249936)
			(end -0.499872 0.249936)
			(stroke
				(width 0.1)
				(type default)
			)
			(layer "F.Fab")
		)
		(pad "A" smd rect
			(at -0.47498 0)
			(size 0.6096 0.7112)
			(layers "F.Cu" "F.Mask" "F.Paste")
			(net "LED_PWRGD_PCH_PWROK_R")
		)
		(pad "C" smd rect
			(at 0.47498 0)
			(size 0.6096 0.7112)
			(layers "F.Cu" "F.Mask" "F.Paste")
			(net "LED_PWRGD_PCH_PWROK_R_D")
		)
	)
)
